# T6G (Grand Teton) — schematic netlist excerpt (pin names and nets, part order shuffled) for the footprints in the layout excerpt that follows; sources: Cadence DE-HDL packaged netlist, KiCad conversion of 04192023_DAF0TMB3IC0_F0TG_MB_C_brd_V02_OCP.brd

C1992  Q_CAP_DIFFBUS  DIFF BUS_0.22UF 6.3V 20% X6S  pkg C0201  page 67 : \1\ = P3E_CPU0_P4_TX_C_DN<2> ; \2\ = P3E_CPU0_P4_TX_DN<2>
C1831  Q_CAP  0.1UF 25V 10% X7R  pkg 0402  page 137 : A = P12V_OCP_V3_2_R ; B = GND
PR6004  Q_RES  11.5K 1% CHIP  pkg 0402LF  page 270 : A = P1V2_AUX_CS ; B = GND

(kicad_pcb
	(version 20260206)
	(generator "pcbnew")
	(generator_version "10.0")
	(general
		(thickness 1.6)
		(legacy_teardrops no)
	)
	(paper "A4")
	(title_block
		(title "04192023_DAF0TMB3IC0_F0TG_MB_C_brd_V02_OCP.brd")
		(comment 1 "Grand Teton / footprints 3213-3215 of 8354")
	)
	(layers
		(0 "F.Cu" signal "TOP")
		(4 "In1.Cu" signal "GND")
		(6 "In2.Cu" signal "IN1")
		(8 "In3.Cu" signal "GND1")
		(10 "In4.Cu" signal "IN2")
		(12 "In5.Cu" signal "GND2")
		(14 "In6.Cu" signal "IN3")
		(16 "In7.Cu" signal "GND3")
		(18 "In8.Cu" signal "VCC")
		(20 "In9.Cu" signal "VCC1")
		(22 "In10.Cu" signal "GND4")
		(24 "In11.Cu" signal "IN4")
		(26 "In12.Cu" signal "GND5")
		(28 "In13.Cu" signal "IN5")
		(30 "In14.Cu" signal "GND6")
		(32 "In15.Cu" signal "IN6")
		(34 "In16.Cu" signal "GND7")
		(2 "B.Cu" signal "BOTTOM")
		(9 "F.Adhes" user "F.Adhesive")
		(11 "B.Adhes" user "B.Adhesive")
		(13 "F.Paste" user "Package Geometry/Pastemask Top")
		(15 "B.Paste" user "Package Geometry/Pastemask Bottom")
		(5 "F.SilkS" user "Ref Des/Silkscreen Top")
		(7 "B.SilkS" user "Ref Des/Silkscreen Bottom")
		(1 "F.Mask" user "Board Geometry/Soldermask Top")
		(3 "B.Mask" user "Board Geometry/Soldermask Bottom")
		(17 "Dwgs.User" user "User.Drawings")
		(19 "Cmts.User" user "User.Comments")
		(21 "Eco1.User" user "User.Eco1")
		(23 "Eco2.User" user "User.Eco2")
		(25 "Edge.Cuts" user "Board Geometry/Outline")
		(27 "Margin" user)
		(31 "F.CrtYd" user "Package Geometry/Place Bound Top")
		(29 "B.CrtYd" user "Package Geometry/Place Bound Bottom")
		(35 "F.Fab" user "Ref Des/Assembly Top")
		(33 "B.Fab" user "Ref Des/Assembly Bottom")
	)
	(footprint ""
		(layer "F.Cu")
		(at 240.854484 -56.527192)
		(property "Reference" "C1992"
			(at 0 0 0)
			(layer "F.SilkS")
			(hide yes)
			(effects
				(font
					(size 1.27 1.27)
				)
			)
		)
		(property "Value" ""
			(at 0 0 0)
			(layer "F.Fab")
			(effects
				(font
					(size 1.27 1.27)
				)
			)
		)
		(duplicate_pad_numbers_are_jumpers no)
		(fp_line
			(start -0.299974 -0.150114)
			(end 0.299974 -0.150114)
			(stroke
				(width 0.1)
				(type default)
			)
			(layer "F.Fab")
		)
		(fp_line
			(start -0.299974 0.150114)
			(end -0.299974 -0.150114)
			(stroke
				(width 0.1)
				(type default)
			)
			(layer "F.Fab")
		)
		(fp_line
			(start 0.299974 -0.150114)
			(end 0.299974 0.150114)
			(stroke
				(width 0.1)
				(type default)
			)
			(layer "F.Fab")
		)
		(fp_line
			(start 0.299974 0.150114)
			(end -0.299974 0.150114)
			(stroke
				(width 0.1)
				(type default)
			)
			(layer "F.Fab")
		)
		(pad "1" smd rect
			(at -0.2667 0)
			(size 0.3048 0.381)
			(layers "F.Cu" "F.Mask" "F.Paste")
			(net "P3E_CPU0_P4_TX_C_DN<2>")
		)
		(pad "2" smd rect
			(at 0.2667 0)
			(size 0.3048 0.381)
			(layers "F.Cu" "F.Mask" "F.Paste")
			(net "P3E_CPU0_P4_TX_DN<2>")
		)
	)
	(footprint ""
		(layer "F.Cu")
		(at 118.287546 -72.91324 -90)
		(property "Reference" "PR6004"
			(at 0 0 270)
			(layer "F.SilkS")
			(hide yes)
			(effects
				(font
					(size 1.27 1.27)
				)
			)
		)
		(property "Value" ""
			(at 0 0 270)
			(layer "F.Fab")
			(effects
				(font
					(size 1.27 1.27)
				)
			)
		)
		(duplicate_pad_numbers_are_jumpers no)
		(fp_line
			(start -0.7874 0.4064)
			(end -0.7874 -0.4064)
			(stroke
				(width 0.1524)
				(type default)
			)
			(layer "F.SilkS")
		)
		(fp_line
			(start 0.7874 0.4064)
			(end -0.7874 0.4064)
			(stroke
				(width 0.1524)
				(type default)
			)
			(layer "F.SilkS")
		)
		(fp_line
			(start -0.7874 -0.4064)
			(end 0.7874 -0.4064)
			(stroke
				(width 0.1524)
				(type default)
			)
			(layer "F.SilkS")
		)
		(fp_line
			(start 0.7874 -0.4064)
			(end 0.7874 0.4064)
			(stroke
				(width 0.1524)
				(type default)
			)
			(layer "F.SilkS")
		)
		(fp_line
			(start -0.67945 0.3048)
			(end -0.67945 -0.305054)
			(stroke
				(width 0.1)
				(type default)
			)
			(layer "F.Fab")
		)
		(fp_line
			(start -0.12065 0.3048)
			(end -0.67945 0.3048)
			(stroke
				(width 0.1)
				(type default)
			)
			(layer "F.Fab")
		)
		(fp_line
			(start 0.120396 0.3048)
			(end 0.120396 0.2794)
			(stroke
				(width 0.1)
				(type default)
			)
			(layer "F.Fab")
		)
		(fp_line
			(start 0.67945 0.3048)
			(end 0.120396 0.3048)
			(stroke
				(width 0.1)
				(type default)
			)
			(layer "F.Fab")
		)
		(fp_line
			(start -0.12065 0.2794)
			(end -0.12065 0.3048)
			(stroke
				(width 0.1)
				(type default)
			)
			(layer "F.Fab")
		)
		(fp_line
			(start 0.120396 0.2794)
			(end -0.12065 0.2794)
			(stroke
				(width 0.1)
				(type default)
			)
			(layer "F.Fab")
		)
		(fp_line
			(start -0.12065 -0.2794)
			(end 0.12065 -0.2794)
			(stroke
				(width 0.1)
				(type default)
			)
			(layer "F.Fab")
		)
		(fp_line
			(start 0.12065 -0.2794)
			(end 0.12065 -0.3048)
			(stroke
				(width 0.1)
				(type default)
			)
			(layer "F.Fab")
		)
		(fp_line
			(start 0.12065 -0.3048)
			(end 0.67945 -0.3048)
			(stroke
				(width 0.1)
				(type default)
			)
			(layer "F.Fab")
		)
		(fp_line
			(start 0.67945 -0.3048)
			(end 0.67945 0.3048)
			(stroke
				(width 0.1)
				(type default)
			)
			(layer "F.Fab")
		)
		(fp_line
			(start -0.67945 -0.305054)
			(end -0.12065 -0.305054)
			(stroke
				(width 0.1)
				(type default)
			)
			(layer "F.Fab")
		)
		(fp_line
			(start -0.12065 -0.305054)
			(end -0.12065 -0.2794)
			(stroke
				(width 0.1)
				(type default)
			)
			(layer "F.Fab")
		)
		(pad "1" smd circle
			(at -0.40005 0 270)
			(size 0 0)
			(layers "F.Cu" "F.Mask" "F.Paste")
			(net "P1V2_AUX_CS")
		)
		(pad "2" smd circle
			(at 0.40005 0 270)
			(size 0 0)
			(layers "F.Cu" "F.Mask" "F.Paste")
			(net "GND")
		)
	)
	(footprint ""
		(layer "F.Cu")
		(at 65.3796 -15.8496 180)
		(property "Reference" "C1831"
			(at 0 0 180)
			(layer "F.SilkS")
			(hide yes)
			(effects
				(font
					(size 1.27 1.27)
				)
			)
		)
		(property "Value" ""
			(at 0 0 180)
			(layer "F.Fab")
			(effects
				(font
					(size 1.27 1.27)
				)
			)
		)
		(duplicate_pad_numbers_are_jumpers no)
		(fp_line
			(start 0.7874 0.4064)
			(end -0.7874 0.4064)
			(stroke
				(width 0.1524)
				(type default)
			)
			(layer "F.SilkS")
		)
		(fp_line
			(start 0.7874 -0.4064)
			(end 0.7874 0.4064)
			(stroke
				(width 0.1524)
				(type default)
			)
			(layer "F.SilkS")
		)
		(fp_line
			(start -0.7874 0.4064)
			(end -0.7874 -0.4064)
			(stroke
				(width 0.1524)
				(type default)
			)
			(layer "F.SilkS")
		)
		(fp_line
			(start -0.7874 -0.4064)
			(end 0.7874 -0.4064)
			(stroke
				(width 0.1524)
				(type default)
			)
			(layer "F.SilkS")
		)
		(fp_line
			(start 0.67945 0.3048)
			(end 0.120396 0.3048)
			(stroke
				(width 0.1)
				(type default)
			)
			(layer "F.Fab")
		)
		(fp_line
			(start 0.67945 -0.3048)
			(end 0.67945 0.3048)
			(stroke
				(width 0.1)
				(type default)
			)
			(layer "F.Fab")
		)
		(fp_line
			(start 0.12065 -0.2794)
			(end 0.12065 -0.3048)
			(stroke
				(width 0.1)
				(type default)
			)
			(layer "F.Fab")
		)
		(fp_line
			(start 0.12065 -0.3048)
			(end 0.67945 -0.3048)
			(stroke
				(width 0.1)
				(type default)
			)
			(layer "F.Fab")
		)
		(fp_line
			(start 0.120396 0.3048)
			(end 0.120396 0.2794)
			(stroke
				(width 0.1)
				(type default)
			)
			(layer "F.Fab")
		)
		(fp_line
			(start 0.120396 0.2794)
			(end -0.12065 0.2794)
			(stroke
				(width 0.1)
				(type default)
			)
			(layer "F.Fab")
		)
		(fp_line
			(start -0.12065 0.3048)
			(end -0.67945 0.3048)
			(stroke
				(width 0.1)
				(type default)
			)
			(layer "F.Fab")
		)
		(fp_line
			(start -0.12065 0.2794)
			(end -0.12065 0.3048)
			(stroke
				(width 0.1)
				(type default)
			)
			(layer "F.Fab")
		)
		(fp_line
			(start -0.12065 -0.2794)
			(end 0.12065 -0.2794)
			(stroke
				(width 0.1)
				(type default)
			)
			(layer "F.Fab")
		)
		(fp_line
			(start -0.12065 -0.305054)
			(end -0.12065 -0.2794)
			(stroke
				(width 0.1)
				(type default)
			)
			(layer "F.Fab")
		)
		(fp_line
			(start -0.67945 0.3048)
			(end -0.67945 -0.305054)
			(stroke
				(width 0.1)
				(type default)
			)
			(layer "F.Fab")
		)
		(fp_line
			(start -0.67945 -0.305054)
			(end -0.12065 -0.305054)
			(stroke
				(width 0.1)
				(type default)
			)
			(layer "F.Fab")
		)
		(pad "1" smd circle
			(at -0.40005 0 180)
			(size 0 0)
			(layers "F.Cu" "F.Mask" "F.Paste")
			(net "P12V_OCP_V3_2_R")
		)
		(pad "2" smd circle
			(at 0.40005 0 180)
			(size 0 0)
			(layers "F.Cu" "F.Mask" "F.Paste")
			(net "GND")
		)
	)
)
